# BASEBOARD_FAB2 (Tioga Pass) — schematic netlist excerpt (pin names and nets, part order shuffled) for the footprints in the layout excerpt that follows; sources: Cadence DE-HDL packaged netlist, KiCad conversion of Wiwynn_Tioga_Pass_MB.brd

C7P1  CAP  100UF 4V 20% X5R  pkg 0805  page 228 : A = PVDDQ_KLM ; B = GND
CT32  CAP  1000PF 50V 10% X7R  pkg 0402LF  page 224 : A = A_TSENSE_PVDDQ_GHJ ; B = GND
R9P18  RES  15.0K 1% CHIP  pkg 0402  page 199 : A = P12V_STBY ; B = PWRGD_P12V_R

(kicad_pcb
	(version 20260206)
	(generator "pcbnew")
	(generator_version "10.0")
	(general
		(thickness 1.6)
		(legacy_teardrops no)
	)
	(paper "A4")
	(title_block
		(title "Wiwynn_Tioga_Pass_MB.brd")
		(comment 1 "Tioga Pass / footprints 4569-4571 of 4770")
	)
	(layers
		(0 "F.Cu" signal "TOP")
		(4 "In1.Cu" signal "L2GND")
		(6 "In2.Cu" signal "L3")
		(8 "In3.Cu" signal "L4GND")
		(10 "In4.Cu" signal "L5")
		(12 "In5.Cu" signal "L6GND")
		(14 "In6.Cu" signal "L7VCC")
		(16 "In7.Cu" signal "L8VCC")
		(18 "In8.Cu" signal "L9GND")
		(20 "In9.Cu" signal "L10")
		(22 "In10.Cu" signal "L11GND")
		(24 "In11.Cu" signal "L12")
		(26 "In12.Cu" signal "L13GND")
		(2 "B.Cu" signal "BOTTOM")
		(9 "F.Adhes" user "F.Adhesive")
		(11 "B.Adhes" user "B.Adhesive")
		(13 "F.Paste" user "Package Geometry/Pastemask Top")
		(15 "B.Paste" user "Package Geometry/Pastemask Bottom")
		(5 "F.SilkS" user "Ref Des/Silkscreen Top")
		(7 "B.SilkS" user "Ref Des/Silkscreen Bottom")
		(1 "F.Mask" user "Board Geometry/Soldermask Top")
		(3 "B.Mask" user "Board Geometry/Soldermask Bottom")
		(17 "Dwgs.User" user "User.Drawings")
		(19 "Cmts.User" user "User.Comments")
		(21 "Eco1.User" user "User.Eco1")
		(23 "Eco2.User" user "User.Eco2")
		(25 "Edge.Cuts" user "Board Geometry/Outline")
		(27 "Margin" user)
		(31 "F.CrtYd" user "Package Geometry/Place Bound Top")
		(29 "B.CrtYd" user "Package Geometry/Place Bound Bottom")
		(35 "F.Fab" user "Ref Des/Assembly Top")
		(33 "B.Fab" user "Ref Des/Assembly Bottom")
	)
	(footprint ""
		(layer "B.Cu")
		(at 109.880654 -85.06714)
		(property "Reference" "C7P1"
			(at 0 0 0)
			(layer "B.SilkS")
			(hide yes)
			(effects
				(font
					(size 1.27 1.27)
				)
				(justify mirror)
			)
		)
		(property "Value" ""
			(at 0 0 0)
			(layer "B.Fab")
			(effects
				(font
					(size 1.27 1.27)
				)
				(justify mirror)
			)
		)
		(duplicate_pad_numbers_are_jumpers no)
		(fp_poly
			(pts
				(xy 0.7239 -0.2159) (xy -0.7239 -0.2159) (xy -0.7239 1.9939) (xy 0.7239 1.9939)
			)
			(stroke
				(width 0)
				(type default)
			)
			(fill no)
			(layer "B.CrtYd")
		)
		(fp_line
			(start -0.7239 -0.2159)
			(end 0.7239 -0.2159)
			(stroke
				(width 0.1)
				(type default)
			)
			(layer "B.Fab")
		)
		(fp_line
			(start -0.7239 1.9939)
			(end -0.7239 -0.2159)
			(stroke
				(width 0.1)
				(type default)
			)
			(layer "B.Fab")
		)
		(fp_line
			(start 0.7239 -0.2159)
			(end 0.7239 1.9939)
			(stroke
				(width 0.1)
				(type default)
			)
			(layer "B.Fab")
		)
		(fp_line
			(start 0.7239 1.9939)
			(end -0.7239 1.9939)
			(stroke
				(width 0.1)
				(type default)
			)
			(layer "B.Fab")
		)
		(pad "1" smd rect
			(at 0 0 180)
			(size 1.27 1.016)
			(layers "B.Cu" "B.Mask" "B.Paste")
			(net "PVDDQ_KLM")
		)
		(pad "2" smd rect
			(at 0 1.778 180)
			(size 1.27 1.016)
			(layers "B.Cu" "B.Mask" "B.Paste")
			(net "GND")
		)
		(zone
			(layer "B.Cu")
			(hatch none 0.5)
			(connect_pads
				(clearance 0)
			)
			(min_thickness 0.25)
			(keepout
				(tracks not_allowed)
				(vias allowed)
				(pads allowed)
				(copperpour not_allowed)
				(footprints allowed)
			)
			(placement
				(enabled no)
				(sheetname "")
			)
			(fill
				(thermal_gap 0.5)
				(thermal_bridge_width 0.5)
				(island_removal_mode 0)
			)
			(polygon
				(pts
					(xy 110.515654 -84.55914) (xy 109.245654 -84.55914) (xy 109.245654 -83.79714) (xy 110.515654 -83.79714)
				)
			)
		)
	)
	(footprint ""
		(layer "B.Cu")
		(at 11.9126 -74.8284 180)
		(property "Reference" "R9P18"
			(at 0 0 0)
			(layer "B.SilkS")
			(hide yes)
			(effects
				(font
					(size 1.27 1.27)
				)
				(justify mirror)
			)
		)
		(property "Value" ""
			(at 0 0 0)
			(layer "B.Fab")
			(effects
				(font
					(size 1.27 1.27)
				)
				(justify mirror)
			)
		)
		(duplicate_pad_numbers_are_jumpers no)
		(fp_rect
			(start 0.2794 -0.1016)
			(end -0.2794 0.9906)
			(stroke
				(width 0)
				(type default)
			)
			(fill no)
			(layer "B.CrtYd")
		)
		(fp_line
			(start 0.2794 0.9906)
			(end -0.2794 0.9906)
			(stroke
				(width 0.1)
				(type default)
			)
			(layer "B.Fab")
		)
		(fp_line
			(start 0.2794 -0.1016)
			(end 0.2794 0.9906)
			(stroke
				(width 0.1)
				(type default)
			)
			(layer "B.Fab")
		)
		(fp_line
			(start -0.2794 0.9906)
			(end -0.2794 -0.1016)
			(stroke
				(width 0.1)
				(type default)
			)
			(layer "B.Fab")
		)
		(fp_line
			(start -0.2794 -0.1016)
			(end 0.2794 -0.1016)
			(stroke
				(width 0.1)
				(type default)
			)
			(layer "B.Fab")
		)
		(pad "1" smd rect
			(at 0 0)
			(size 0.508 0.508)
			(layers "B.Cu" "B.Mask" "B.Paste")
			(net "P12V_STBY")
		)
		(pad "2" smd rect
			(at 0 0.889)
			(size 0.508 0.508)
			(layers "B.Cu" "B.Mask" "B.Paste")
			(net "PWRGD_P12V_R")
		)
		(zone
			(layer "B.Cu")
			(hatch none 0.5)
			(connect_pads
				(clearance 0)
			)
			(min_thickness 0.25)
			(keepout
				(tracks allowed)
				(vias not_allowed)
				(pads allowed)
				(copperpour not_allowed)
				(footprints allowed)
			)
			(placement
				(enabled no)
				(sheetname "")
			)
			(fill
				(thermal_gap 0.5)
				(thermal_bridge_width 0.5)
				(island_removal_mode 0)
			)
			(polygon
				(pts
					(xy 11.6586 -75.0824) (xy 12.1666 -75.0824) (xy 12.1666 -75.4634) (xy 11.6586 -75.4634)
				)
			)
		)
		(zone
			(layer "B.Cu")
			(hatch none 0.5)
			(connect_pads
				(clearance 0)
			)
			(min_thickness 0.25)
			(keepout
				(tracks not_allowed)
				(vias allowed)
				(pads allowed)
				(copperpour not_allowed)
				(footprints allowed)
			)
			(placement
				(enabled no)
				(sheetname "")
			)
			(fill
				(thermal_gap 0.5)
				(thermal_bridge_width 0.5)
				(island_removal_mode 0)
			)
			(polygon
				(pts
					(xy 11.6586 -75.0824) (xy 12.1666 -75.0824) (xy 12.1666 -75.4634) (xy 11.6586 -75.4634)
				)
			)
		)
	)
	(footprint ""
		(layer "B.Cu")
		(at 1.27 -15.9512 90)
		(property "Reference" "CT32"
			(at 0.8382 -0.84963 90)
			(unlocked yes)
			(layer "B.SilkS")
			(effects
				(font
					(size 0.7874 0.5842)
					(thickness 0.1524)
				)
				(justify left mirror)
			)
		)
		(property "Value" ""
			(at 0 0 90)
			(layer "B.Fab")
			(effects
				(font
					(size 1.27 1.27)
				)
				(justify mirror)
			)
		)
		(duplicate_pad_numbers_are_jumpers no)
		(fp_poly
			(pts
				(xy -0.3048 -0.1016) (xy -0.3048 0.9906) (xy 0.3048 0.9906) (xy 0.3048 -0.1016)
			)
			(stroke
				(width 0)
				(type default)
			)
			(fill no)
			(layer "B.CrtYd")
		)
		(fp_line
			(start 0.3048 -0.1016)
			(end 0.3048 0.9906)
			(stroke
				(width 0.1)
				(type default)
			)
			(layer "B.Fab")
		)
		(fp_line
			(start -0.3048 -0.1016)
			(end 0.3048 -0.1016)
			(stroke
				(width 0.1)
				(type default)
			)
			(layer "B.Fab")
		)
		(fp_line
			(start 0.3048 0.9906)
			(end -0.3048 0.9906)
			(stroke
				(width 0.1)
				(type default)
			)
			(layer "B.Fab")
		)
		(fp_line
			(start -0.3048 0.9906)
			(end -0.3048 -0.1016)
			(stroke
				(width 0.1)
				(type default)
			)
			(layer "B.Fab")
		)
		(pad "1" smd rect
			(at 0 0 270)
			(size 0.508 0.508)
			(layers "B.Cu" "B.Mask" "B.Paste")
			(net "A_TSENSE_PVDDQ_GHJ")
		)
		(pad "2" smd rect
			(at 0 0.889 270)
			(size 0.508 0.508)
			(layers "B.Cu" "B.Mask" "B.Paste")
			(net "GND")
		)
		(zone
			(layer "B.Cu")
			(hatch none 0.5)
			(connect_pads
				(clearance 0)
			)
			(min_thickness 0.25)
			(keepout
				(tracks allowed)
				(vias not_allowed)
				(pads allowed)
				(copperpour not_allowed)
				(footprints allowed)
			)
			(placement
				(enabled no)
				(sheetname "")
			)
			(fill
				(thermal_gap 0.5)
				(thermal_bridge_width 0.5)
				(island_removal_mode 0)
			)
			(polygon
				(pts
					(xy 1.524 -16.2052) (xy 1.524 -15.6972) (xy 1.905 -15.6972) (xy 1.905 -16.2052)
				)
			)
		)
		(zone
			(layer "B.Cu")
			(hatch none 0.5)
			(connect_pads
				(clearance 0)
			)
			(min_thickness 0.25)
			(keepout
				(tracks not_allowed)
				(vias allowed)
				(pads allowed)
				(copperpour not_allowed)
				(footprints allowed)
			)
			(placement
				(enabled no)
				(sheetname "")
			)
			(fill
				(thermal_gap 0.5)
				(thermal_bridge_width 0.5)
				(island_removal_mode 0)
			)
			(polygon
				(pts
					(xy 1.905 -16.2052) (xy 1.905 -15.6972) (xy 1.524 -15.6972) (xy 1.524 -16.2052)
				)
			)
		)
	)
)
